# S9S_MB_2U (Grand Teton) — schematic netlist excerpt (pin names and nets, part order shuffled) for the footprints in the layout excerpt that follows; sources: Cadence DE-HDL packaged netlist, KiCad conversion of 03242023_DA0F0TMBIJ0_F0T_Motherboard_J_brd_V01_OCP.brd

R4059  Q_RES  0 5% EMPTY  pkg 0402LF  page 162 : A = HP_LVC3_OCP_V3_2_EN ; B = P12V_OCP_EN_2_R
C1825  Q_CAP  0.1UF 25V 10% X7R  pkg 0402  page 160 : A = P3V3_AUX ; B = GND
C721  Q_CAP_DIFFBUS  DIFF BUS_0.22UF 6.3V 20% X6S  pkg C0201  page 176 : \1\ = P5E_CPU1_PE0_TX_C_DP<10> ; \2\ = P5E_CPU1_PE0_TX_DP<10>

(kicad_pcb
	(version 20260206)
	(generator "pcbnew")
	(generator_version "10.0")
	(general
		(thickness 1.6)
		(legacy_teardrops no)
	)
	(paper "A4")
	(title_block
		(title "03242023_DA0F0TMBIJ0_F0T_Motherboard_J_brd_V01_OCP.brd")
		(comment 1 "Grand Teton / footprints 3637-3639 of 6105")
	)
	(layers
		(0 "F.Cu" signal "TOP")
		(4 "In1.Cu" signal "GND")
		(6 "In2.Cu" signal "IN1")
		(8 "In3.Cu" signal "GND1")
		(10 "In4.Cu" signal "IN2")
		(12 "In5.Cu" signal "GND2")
		(14 "In6.Cu" signal "IN3")
		(16 "In7.Cu" signal "GND3")
		(18 "In8.Cu" signal "VCC")
		(20 "In9.Cu" signal "VCC1")
		(22 "In10.Cu" signal "GND4")
		(24 "In11.Cu" signal "IN4")
		(26 "In12.Cu" signal "GND5")
		(28 "In13.Cu" signal "IN5")
		(30 "In14.Cu" signal "GND6")
		(32 "In15.Cu" signal "IN6")
		(34 "In16.Cu" signal "GND7")
		(2 "B.Cu" signal "BOTTOM")
		(9 "F.Adhes" user "F.Adhesive")
		(11 "B.Adhes" user "B.Adhesive")
		(13 "F.Paste" user "Package Geometry/Pastemask Top")
		(15 "B.Paste" user "Package Geometry/Pastemask Bottom")
		(5 "F.SilkS" user "Ref Des/Silkscreen Top")
		(7 "B.SilkS" user "Ref Des/Silkscreen Bottom")
		(1 "F.Mask" user "Board Geometry/Soldermask Top")
		(3 "B.Mask" user "Board Geometry/Soldermask Bottom")
		(17 "Dwgs.User" user "User.Drawings")
		(19 "Cmts.User" user "User.Comments")
		(21 "Eco1.User" user "User.Eco1")
		(23 "Eco2.User" user "User.Eco2")
		(25 "Edge.Cuts" user "Board Geometry/Outline")
		(27 "Margin" user)
		(31 "F.CrtYd" user "Package Geometry/Place Bound Top")
		(29 "B.CrtYd" user "Package Geometry/Place Bound Bottom")
		(35 "F.Fab" user "Ref Des/Assembly Top")
		(33 "B.Fab" user "Ref Des/Assembly Bottom")
	)
	(footprint ""
		(layer "F.Cu")
		(at 151.5872 -127.897128 90)
		(property "Reference" "C1825"
			(at 0 0 90)
			(layer "F.SilkS")
			(hide yes)
			(effects
				(font
					(size 1.27 1.27)
				)
			)
		)
		(property "Value" ""
			(at 0 0 90)
			(layer "F.Fab")
			(effects
				(font
					(size 1.27 1.27)
				)
			)
		)
		(duplicate_pad_numbers_are_jumpers no)
		(fp_line
			(start 0.7874 -0.4064)
			(end 0.7874 0.4064)
			(stroke
				(width 0.1524)
				(type default)
			)
			(layer "F.SilkS")
		)
		(fp_line
			(start -0.7874 -0.4064)
			(end 0.7874 -0.4064)
			(stroke
				(width 0.1524)
				(type default)
			)
			(layer "F.SilkS")
		)
		(fp_line
			(start 0.7874 0.4064)
			(end -0.7874 0.4064)
			(stroke
				(width 0.1524)
				(type default)
			)
			(layer "F.SilkS")
		)
		(fp_line
			(start -0.7874 0.4064)
			(end -0.7874 -0.4064)
			(stroke
				(width 0.1524)
				(type default)
			)
			(layer "F.SilkS")
		)
		(fp_line
			(start -0.12065 -0.305054)
			(end -0.12065 -0.2794)
			(stroke
				(width 0.1)
				(type default)
			)
			(layer "F.Fab")
		)
		(fp_line
			(start -0.67945 -0.305054)
			(end -0.12065 -0.305054)
			(stroke
				(width 0.1)
				(type default)
			)
			(layer "F.Fab")
		)
		(fp_line
			(start 0.67945 -0.3048)
			(end 0.67945 0.3048)
			(stroke
				(width 0.1)
				(type default)
			)
			(layer "F.Fab")
		)
		(fp_line
			(start 0.12065 -0.3048)
			(end 0.67945 -0.3048)
			(stroke
				(width 0.1)
				(type default)
			)
			(layer "F.Fab")
		)
		(fp_line
			(start 0.12065 -0.2794)
			(end 0.12065 -0.3048)
			(stroke
				(width 0.1)
				(type default)
			)
			(layer "F.Fab")
		)
		(fp_line
			(start -0.12065 -0.2794)
			(end 0.12065 -0.2794)
			(stroke
				(width 0.1)
				(type default)
			)
			(layer "F.Fab")
		)
		(fp_line
			(start 0.120396 0.2794)
			(end -0.12065 0.2794)
			(stroke
				(width 0.1)
				(type default)
			)
			(layer "F.Fab")
		)
		(fp_line
			(start -0.12065 0.2794)
			(end -0.12065 0.3048)
			(stroke
				(width 0.1)
				(type default)
			)
			(layer "F.Fab")
		)
		(fp_line
			(start 0.67945 0.3048)
			(end 0.120396 0.3048)
			(stroke
				(width 0.1)
				(type default)
			)
			(layer "F.Fab")
		)
		(fp_line
			(start 0.120396 0.3048)
			(end 0.120396 0.2794)
			(stroke
				(width 0.1)
				(type default)
			)
			(layer "F.Fab")
		)
		(fp_line
			(start -0.12065 0.3048)
			(end -0.67945 0.3048)
			(stroke
				(width 0.1)
				(type default)
			)
			(layer "F.Fab")
		)
		(fp_line
			(start -0.67945 0.3048)
			(end -0.67945 -0.305054)
			(stroke
				(width 0.1)
				(type default)
			)
			(layer "F.Fab")
		)
		(pad "1" smd circle
			(at -0.40005 0 90)
			(size 0 0)
			(layers "F.Cu" "F.Mask" "F.Paste")
			(net "P3V3_AUX")
		)
		(pad "2" smd circle
			(at 0.40005 0 90)
			(size 0 0)
			(layers "F.Cu" "F.Mask" "F.Paste")
			(net "GND")
		)
	)
	(footprint ""
		(layer "F.Cu")
		(at 66.022982 -36.906708 90)
		(property "Reference" "R4059"
			(at 0 0 90)
			(layer "F.SilkS")
			(hide yes)
			(effects
				(font
					(size 1.27 1.27)
				)
			)
		)
		(property "Value" ""
			(at 0 0 90)
			(layer "F.Fab")
			(effects
				(font
					(size 1.27 1.27)
				)
			)
		)
		(duplicate_pad_numbers_are_jumpers no)
		(fp_line
			(start 0.7874 -0.4064)
			(end 0.7874 0.4064)
			(stroke
				(width 0.1524)
				(type default)
			)
			(layer "F.SilkS")
		)
		(fp_line
			(start -0.7874 -0.4064)
			(end 0.7874 -0.4064)
			(stroke
				(width 0.1524)
				(type default)
			)
			(layer "F.SilkS")
		)
		(fp_line
			(start 0.7874 0.4064)
			(end -0.7874 0.4064)
			(stroke
				(width 0.1524)
				(type default)
			)
			(layer "F.SilkS")
		)
		(fp_line
			(start -0.7874 0.4064)
			(end -0.7874 -0.4064)
			(stroke
				(width 0.1524)
				(type default)
			)
			(layer "F.SilkS")
		)
		(fp_line
			(start -0.12065 -0.305054)
			(end -0.12065 -0.2794)
			(stroke
				(width 0.1)
				(type default)
			)
			(layer "F.Fab")
		)
		(fp_line
			(start -0.67945 -0.305054)
			(end -0.12065 -0.305054)
			(stroke
				(width 0.1)
				(type default)
			)
			(layer "F.Fab")
		)
		(fp_line
			(start 0.67945 -0.3048)
			(end 0.67945 0.3048)
			(stroke
				(width 0.1)
				(type default)
			)
			(layer "F.Fab")
		)
		(fp_line
			(start 0.12065 -0.3048)
			(end 0.67945 -0.3048)
			(stroke
				(width 0.1)
				(type default)
			)
			(layer "F.Fab")
		)
		(fp_line
			(start 0.12065 -0.2794)
			(end 0.12065 -0.3048)
			(stroke
				(width 0.1)
				(type default)
			)
			(layer "F.Fab")
		)
		(fp_line
			(start -0.12065 -0.2794)
			(end 0.12065 -0.2794)
			(stroke
				(width 0.1)
				(type default)
			)
			(layer "F.Fab")
		)
		(fp_line
			(start 0.120396 0.2794)
			(end -0.12065 0.2794)
			(stroke
				(width 0.1)
				(type default)
			)
			(layer "F.Fab")
		)
		(fp_line
			(start -0.12065 0.2794)
			(end -0.12065 0.3048)
			(stroke
				(width 0.1)
				(type default)
			)
			(layer "F.Fab")
		)
		(fp_line
			(start 0.67945 0.3048)
			(end 0.120396 0.3048)
			(stroke
				(width 0.1)
				(type default)
			)
			(layer "F.Fab")
		)
		(fp_line
			(start 0.120396 0.3048)
			(end 0.120396 0.2794)
			(stroke
				(width 0.1)
				(type default)
			)
			(layer "F.Fab")
		)
		(fp_line
			(start -0.12065 0.3048)
			(end -0.67945 0.3048)
			(stroke
				(width 0.1)
				(type default)
			)
			(layer "F.Fab")
		)
		(fp_line
			(start -0.67945 0.3048)
			(end -0.67945 -0.305054)
			(stroke
				(width 0.1)
				(type default)
			)
			(layer "F.Fab")
		)
		(pad "1" smd circle
			(at -0.40005 0 90)
			(size 0 0)
			(layers "F.Cu" "F.Mask" "F.Paste")
			(net "HP_LVC3_OCP_V3_2_EN")
		)
		(pad "2" smd circle
			(at 0.40005 0 90)
			(size 0 0)
			(layers "F.Cu" "F.Mask" "F.Paste")
			(net "P12V_OCP_EN_2_R")
		)
	)
	(footprint ""
		(layer "F.Cu")
		(at 64.185038 -402.371052 -90)
		(property "Reference" "C721"
			(at 0 0 270)
			(layer "F.SilkS")
			(hide yes)
			(effects
				(font
					(size 1.27 1.27)
				)
			)
		)
		(property "Value" ""
			(at 0 0 270)
			(layer "F.Fab")
			(effects
				(font
					(size 1.27 1.27)
				)
			)
		)
		(duplicate_pad_numbers_are_jumpers no)
		(fp_line
			(start -0.299974 0.150114)
			(end -0.299974 -0.150114)
			(stroke
				(width 0.1)
				(type default)
			)
			(layer "F.Fab")
		)
		(fp_line
			(start 0.299974 0.150114)
			(end -0.299974 0.150114)
			(stroke
				(width 0.1)
				(type default)
			)
			(layer "F.Fab")
		)
		(fp_line
			(start -0.299974 -0.150114)
			(end 0.299974 -0.150114)
			(stroke
				(width 0.1)
				(type default)
			)
			(layer "F.Fab")
		)
		(fp_line
			(start 0.299974 -0.150114)
			(end 0.299974 0.150114)
			(stroke
				(width 0.1)
				(type default)
			)
			(layer "F.Fab")
		)
		(pad "1" smd rect
			(at -0.2667 0 270)
			(size 0.3048 0.381)
			(layers "F.Cu" "F.Mask" "F.Paste")
			(net "P5E_CPU1_PE0_TX_C_DP<10>")
		)
		(pad "2" smd rect
			(at 0.2667 0 270)
			(size 0.3048 0.381)
			(layers "F.Cu" "F.Mask" "F.Paste")
			(net "P5E_CPU1_PE0_TX_DP<10>")
		)
	)
)
